(kicad_pcb
	(version 20260206)
	(generator "pcbnew")
	(generator_version "10.0")
	(general
		(thickness 1.6)
		(legacy_teardrops no)
	)
	(paper "A4")
	(title_block
		(title "01162023_DA0F0TEBIF0_F0T_Expander_BD_F_brd_V02_OCP.brd")
		(comment 1 "Grand Teton / footprints 5005-5011 of 9728")
	)
	(layers
		(0 "F.Cu" signal "TOP")
		(4 "In1.Cu" signal "GND")
		(6 "In2.Cu" signal "VCC")
		(8 "In3.Cu" signal "VCC1")
		(10 "In4.Cu" signal "GND1")
		(12 "In5.Cu" signal "IN1")
		(14 "In6.Cu" signal "GND2")
		(16 "In7.Cu" signal "IN2")
		(18 "In8.Cu" signal "GND3")
		(20 "In9.Cu" signal "IN3")
		(22 "In10.Cu" signal "GND4")
		(24 "In11.Cu" signal "IN4")
		(26 "In12.Cu" signal "GND5")
		(28 "In13.Cu" signal "IN5")
		(30 "In14.Cu" signal "GND6")
		(32 "In15.Cu" signal "IN6")
		(34 "In16.Cu" signal "GND7")
		(2 "B.Cu" signal "BOTTOM")
		(9 "F.Adhes" user "F.Adhesive")
		(11 "B.Adhes" user "B.Adhesive")
		(13 "F.Paste" user "Package Geometry/Pastemask Top")
		(15 "B.Paste" user "Package Geometry/Pastemask Bottom")
		(5 "F.SilkS" user "Ref Des/Silkscreen Top")
		(7 "B.SilkS" user "Ref Des/Silkscreen Bottom")
		(1 "F.Mask" user "Board Geometry/Soldermask Top")
		(3 "B.Mask" user "Board Geometry/Soldermask Bottom")
		(17 "Dwgs.User" user "User.Drawings")
		(19 "Cmts.User" user "User.Comments")
		(21 "Eco1.User" user "User.Eco1")
		(23 "Eco2.User" user "User.Eco2")
		(25 "Edge.Cuts" user "Board Geometry/Outline")
		(27 "Margin" user)
		(31 "F.CrtYd" user "Package Geometry/Place Bound Top")
		(29 "B.CrtYd" user "Package Geometry/Place Bound Bottom")
		(35 "F.Fab" user "Ref Des/Assembly Top")
		(33 "B.Fab" user "Ref Des/Assembly Bottom")
	)
	(footprint ""
		(layer "F.Cu")
		(at 371.802152 -254.850646 180)
		(property "Reference" "D4"
			(at 1.113282 -1.346454 0)
			(unlocked yes)
			(layer "F.SilkS")
			(effects
				(font
					(size 0.7874 0.5842)
					(thickness 0.1524)
				)
				(justify left)
			)
		)
		(property "Value" ""
			(at 0 0 180)
			(layer "F.Fab")
			(effects
				(font
					(size 1.27 1.27)
				)
			)
		)
		(duplicate_pad_numbers_are_jumpers no)
		(fp_line
			(start 1.16078 0.4826)
			(end -0.64008 0.4826)
			(stroke
				(width 0.1524)
				(type default)
			)
			(layer "F.SilkS")
		)
		(fp_line
			(start 1.16078 -0.4826)
			(end 1.16078 0.4826)
			(stroke
				(width 0.1524)
				(type default)
			)
			(layer "F.SilkS")
		)
		(fp_line
			(start 1.03378 0.4826)
			(end -0.79248 0.4826)
			(stroke
				(width 0.1524)
				(type default)
			)
			(layer "F.SilkS")
		)
		(fp_line
			(start 1.03378 -0.4826)
			(end 1.03378 0.4826)
			(stroke
				(width 0.1524)
				(type default)
			)
			(layer "F.SilkS")
		)
		(fp_line
			(start 0.90678 0.4826)
			(end -0.90678 0.4826)
			(stroke
				(width 0.1524)
				(type default)
			)
			(layer "F.SilkS")
		)
		(fp_line
			(start 0.90678 -0.4826)
			(end 0.90678 0.4826)
			(stroke
				(width 0.1524)
				(type default)
			)
			(layer "F.SilkS")
		)
		(fp_line
			(start -0.64008 -0.4826)
			(end 1.16078 -0.4826)
			(stroke
				(width 0.1524)
				(type default)
			)
			(layer "F.SilkS")
		)
		(fp_line
			(start -0.79248 -0.4826)
			(end 1.03378 -0.4826)
			(stroke
				(width 0.1524)
				(type default)
			)
			(layer "F.SilkS")
		)
		(fp_line
			(start -0.89408 -0.4826)
			(end 0.90678 -0.4826)
			(stroke
				(width 0.1524)
				(type default)
			)
			(layer "F.SilkS")
		)
		(fp_line
			(start -0.90678 0.4826)
			(end -0.90678 -0.4699)
			(stroke
				(width 0.1524)
				(type default)
			)
			(layer "F.SilkS")
		)
		(fp_line
			(start 0.499872 0.249936)
			(end -0.499872 0.249936)
			(stroke
				(width 0.1)
				(type default)
			)
			(layer "F.Fab")
		)
		(fp_line
			(start 0.499872 -0.249936)
			(end 0.499872 0.249936)
			(stroke
				(width 0.1)
				(type default)
			)
			(layer "F.Fab")
		)
		(fp_line
			(start -0.499872 0.249936)
			(end -0.499872 -0.249936)
			(stroke
				(width 0.1)
				(type default)
			)
			(layer "F.Fab")
		)
		(fp_line
			(start -0.499872 -0.249936)
			(end 0.499872 -0.249936)
			(stroke
				(width 0.1)
				(type default)
			)
			(layer "F.Fab")
		)
		(pad "A" smd rect
			(at -0.47498 0 180)
			(size 0.6096 0.7112)
			(layers "F.Cu" "F.Mask" "F.Paste")
			(net "LED_PEX3_SYS_ERR_N")
		)
		(pad "C" smd rect
			(at 0.47498 0 180)
			(size 0.6096 0.7112)
			(layers "F.Cu" "F.Mask" "F.Paste")
			(net "PEX3_SYS_ERR_3V3_N")
		)
	)
	(footprint ""
		(layer "F.Cu")
		(at 323.834252 -310.478932 -45)
		(property "Reference" "R3945"
			(at 0 0 315)
			(layer "F.SilkS")
			(hide yes)
			(effects
				(font
					(size 1.27 1.27)
				)
			)
		)
		(property "Value" ""
			(at 0 0 315)
			(layer "F.Fab")
			(effects
				(font
					(size 1.27 1.27)
				)
			)
		)
		(duplicate_pad_numbers_are_jumpers no)
		(fp_line
			(start -0.787389 0.406267)
			(end -0.787389 -0.406267)
			(stroke
				(width 0.1524)
				(type default)
			)
			(layer "F.SilkS")
		)
		(fp_line
			(start -0.787389 -0.406267)
			(end 0.787389 -0.406267)
			(stroke
				(width 0.1524)
				(type default)
			)
			(layer "F.SilkS")
		)
		(fp_line
			(start 0.787389 0.406267)
			(end -0.787389 0.406267)
			(stroke
				(width 0.1524)
				(type default)
			)
			(layer "F.SilkS")
		)
		(fp_line
			(start 0.787389 -0.406267)
			(end 0.787389 0.406267)
			(stroke
				(width 0.1524)
				(type default)
			)
			(layer "F.SilkS")
		)
		(fp_line
			(start -0.679446 0.30479)
			(end -0.679446 -0.305149)
			(stroke
				(width 0.1)
				(type default)
			)
			(layer "F.Fab")
		)
		(fp_line
			(start -0.120515 0.30479)
			(end -0.679446 0.30479)
			(stroke
				(width 0.1)
				(type default)
			)
			(layer "F.Fab")
		)
		(fp_line
			(start -0.120695 0.279466)
			(end -0.120515 0.30479)
			(stroke
				(width 0.1)
				(type default)
			)
			(layer "F.Fab")
		)
		(fp_line
			(start -0.679446 -0.305149)
			(end -0.120695 -0.304969)
			(stroke
				(width 0.1)
				(type default)
			)
			(layer "F.Fab")
		)
		(fp_line
			(start 0.120515 0.30479)
			(end 0.120335 0.279466)
			(stroke
				(width 0.1)
				(type default)
			)
			(layer "F.Fab")
		)
		(fp_line
			(start 0.120335 0.279466)
			(end -0.120695 0.279466)
			(stroke
				(width 0.1)
				(type default)
			)
			(layer "F.Fab")
		)
		(fp_line
			(start -0.120695 -0.279466)
			(end 0.120695 -0.279466)
			(stroke
				(width 0.1)
				(type default)
			)
			(layer "F.Fab")
		)
		(fp_line
			(start -0.120695 -0.304969)
			(end -0.120695 -0.279466)
			(stroke
				(width 0.1)
				(type default)
			)
			(layer "F.Fab")
		)
		(fp_line
			(start 0.679446 0.30479)
			(end 0.120515 0.30479)
			(stroke
				(width 0.1)
				(type default)
			)
			(layer "F.Fab")
		)
		(fp_line
			(start 0.120695 -0.279466)
			(end 0.120515 -0.30479)
			(stroke
				(width 0.1)
				(type default)
			)
			(layer "F.Fab")
		)
		(fp_line
			(start 0.120515 -0.30479)
			(end 0.679446 -0.30479)
			(stroke
				(width 0.1)
				(type default)
			)
			(layer "F.Fab")
		)
		(fp_line
			(start 0.679446 -0.30479)
			(end 0.679446 0.30479)
			(stroke
				(width 0.1)
				(type default)
			)
			(layer "F.Fab")
		)
		(pad "1" smd circle
			(at -0.40005 0 315)
			(size 0 0)
			(layers "F.Cu" "F.Mask" "F.Paste")
			(net "PU_PEX2_SIO_BLINK")
		)
		(pad "2" smd circle
			(at 0.40005 0 315)
			(size 0 0)
			(layers "F.Cu" "F.Mask" "F.Paste")
			(net "P1V8_PEX")
		)
	)
	(footprint ""
		(layer "F.Cu")
		(at 366.955578 -82.641694 180)
		(property "Reference" "R1618"
			(at 0 0 180)
			(layer "F.SilkS")
			(hide yes)
			(effects
				(font
					(size 1.27 1.27)
				)
			)
		)
		(property "Value" ""
			(at 0 0 180)
			(layer "F.Fab")
			(effects
				(font
					(size 1.27 1.27)
				)
			)
		)
		(duplicate_pad_numbers_are_jumpers no)
		(fp_line
			(start 0.7874 0.4064)
			(end -0.7874 0.4064)
			(stroke
				(width 0.1524)
				(type default)
			)
			(layer "F.SilkS")
		)
		(fp_line
			(start 0.7874 -0.4064)
			(end 0.7874 0.4064)
			(stroke
				(width 0.1524)
				(type default)
			)
			(layer "F.SilkS")
		)
		(fp_line
			(start -0.7874 0.4064)
			(end -0.7874 -0.4064)
			(stroke
				(width 0.1524)
				(type default)
			)
			(layer "F.SilkS")
		)
		(fp_line
			(start -0.7874 -0.4064)
			(end 0.7874 -0.4064)
			(stroke
				(width 0.1524)
				(type default)
			)
			(layer "F.SilkS")
		)
		(fp_line
			(start 0.67945 0.3048)
			(end 0.120396 0.3048)
			(stroke
				(width 0.1)
				(type default)
			)
			(layer "F.Fab")
		)
		(fp_line
			(start 0.67945 -0.3048)
			(end 0.67945 0.3048)
			(stroke
				(width 0.1)
				(type default)
			)
			(layer "F.Fab")
		)
		(fp_line
			(start 0.12065 -0.2794)
			(end 0.12065 -0.3048)
			(stroke
				(width 0.1)
				(type default)
			)
			(layer "F.Fab")
		)
		(fp_line
			(start 0.12065 -0.3048)
			(end 0.67945 -0.3048)
			(stroke
				(width 0.1)
				(type default)
			)
			(layer "F.Fab")
		)
		(fp_line
			(start 0.120396 0.3048)
			(end 0.120396 0.2794)
			(stroke
				(width 0.1)
				(type default)
			)
			(layer "F.Fab")
		)
		(fp_line
			(start 0.120396 0.2794)
			(end -0.12065 0.2794)
			(stroke
				(width 0.1)
				(type default)
			)
			(layer "F.Fab")
		)
		(fp_line
			(start -0.12065 0.3048)
			(end -0.67945 0.3048)
			(stroke
				(width 0.1)
				(type default)
			)
			(layer "F.Fab")
		)
		(fp_line
			(start -0.12065 0.2794)
			(end -0.12065 0.3048)
			(stroke
				(width 0.1)
				(type default)
			)
			(layer "F.Fab")
		)
		(fp_line
			(start -0.12065 -0.2794)
			(end 0.12065 -0.2794)
			(stroke
				(width 0.1)
				(type default)
			)
			(layer "F.Fab")
		)
		(fp_line
			(start -0.12065 -0.305054)
			(end -0.12065 -0.2794)
			(stroke
				(width 0.1)
				(type default)
			)
			(layer "F.Fab")
		)
		(fp_line
			(start -0.67945 0.3048)
			(end -0.67945 -0.305054)
			(stroke
				(width 0.1)
				(type default)
			)
			(layer "F.Fab")
		)
		(fp_line
			(start -0.67945 -0.305054)
			(end -0.12065 -0.305054)
			(stroke
				(width 0.1)
				(type default)
			)
			(layer "F.Fab")
		)
		(pad "1" smd circle
			(at -0.40005 0 180)
			(size 0 0)
			(layers "F.Cu" "F.Mask" "F.Paste")
			(net "SMB_BIC_I2C9_MUX1_SSD12_R_SCL")
		)
		(pad "2" smd circle
			(at 0.40005 0 180)
			(size 0 0)
			(layers "F.Cu" "F.Mask" "F.Paste")
			(net "SMB_BIC_I2C9_MUX1_SSD12_SCL")
		)
	)
	(footprint ""
		(layer "F.Cu")
		(at 240.03889 -211.266278 90)
		(property "Reference" "R480"
			(at 0 0 90)
			(layer "F.SilkS")
			(hide yes)
			(effects
				(font
					(size 1.27 1.27)
				)
			)
		)
		(property "Value" ""
			(at 0 0 90)
			(layer "F.Fab")
			(effects
				(font
					(size 1.27 1.27)
				)
			)
		)
		(duplicate_pad_numbers_are_jumpers no)
		(fp_line
			(start 0.7874 -0.4064)
			(end 0.7874 0.4064)
			(stroke
				(width 0.1524)
				(type default)
			)
			(layer "F.SilkS")
		)
		(fp_line
			(start -0.7874 -0.4064)
			(end 0.7874 -0.4064)
			(stroke
				(width 0.1524)
				(type default)
			)
			(layer "F.SilkS")
		)
		(fp_line
			(start 0.7874 0.4064)
			(end -0.7874 0.4064)
			(stroke
				(width 0.1524)
				(type default)
			)
			(layer "F.SilkS")
		)
		(fp_line
			(start -0.7874 0.4064)
			(end -0.7874 -0.4064)
			(stroke
				(width 0.1524)
				(type default)
			)
			(layer "F.SilkS")
		)
		(fp_line
			(start -0.12065 -0.305054)
			(end -0.12065 -0.2794)
			(stroke
				(width 0.1)
				(type default)
			)
			(layer "F.Fab")
		)
		(fp_line
			(start -0.67945 -0.305054)
			(end -0.12065 -0.305054)
			(stroke
				(width 0.1)
				(type default)
			)
			(layer "F.Fab")
		)
		(fp_line
			(start 0.67945 -0.3048)
			(end 0.67945 0.3048)
			(stroke
				(width 0.1)
				(type default)
			)
			(layer "F.Fab")
		)
		(fp_line
			(start 0.12065 -0.3048)
			(end 0.67945 -0.3048)
			(stroke
				(width 0.1)
				(type default)
			)
			(layer "F.Fab")
		)
		(fp_line
			(start 0.12065 -0.2794)
			(end 0.12065 -0.3048)
			(stroke
				(width 0.1)
				(type default)
			)
			(layer "F.Fab")
		)
		(fp_line
			(start -0.12065 -0.2794)
			(end 0.12065 -0.2794)
			(stroke
				(width 0.1)
				(type default)
			)
			(layer "F.Fab")
		)
		(fp_line
			(start 0.120396 0.2794)
			(end -0.12065 0.2794)
			(stroke
				(width 0.1)
				(type default)
			)
			(layer "F.Fab")
		)
		(fp_line
			(start -0.12065 0.2794)
			(end -0.12065 0.3048)
			(stroke
				(width 0.1)
				(type default)
			)
			(layer "F.Fab")
		)
		(fp_line
			(start 0.67945 0.3048)
			(end 0.120396 0.3048)
			(stroke
				(width 0.1)
				(type default)
			)
			(layer "F.Fab")
		)
		(fp_line
			(start 0.120396 0.3048)
			(end 0.120396 0.2794)
			(stroke
				(width 0.1)
				(type default)
			)
			(layer "F.Fab")
		)
		(fp_line
			(start -0.12065 0.3048)
			(end -0.67945 0.3048)
			(stroke
				(width 0.1)
				(type default)
			)
			(layer "F.Fab")
		)
		(fp_line
			(start -0.67945 0.3048)
			(end -0.67945 -0.305054)
			(stroke
				(width 0.1)
				(type default)
			)
			(layer "F.Fab")
		)
		(pad "1" smd circle
			(at -0.40005 0 90)
			(size 0 0)
			(layers "F.Cu" "F.Mask" "F.Paste")
			(net "P3V3_SCALED")
		)
		(pad "2" smd circle
			(at 0.40005 0 90)
			(size 0 0)
			(layers "F.Cu" "F.Mask" "F.Paste")
			(net "GND")
		)
	)
	(footprint ""
		(layer "F.Cu")
		(at 235.623608 -145.688812)
		(property "Reference" "R4223"
			(at 0 0 0)
			(layer "F.SilkS")
			(hide yes)
			(effects
				(font
					(size 1.27 1.27)
				)
			)
		)
		(property "Value" ""
			(at 0 0 0)
			(layer "F.Fab")
			(effects
				(font
					(size 1.27 1.27)
				)
			)
		)
		(duplicate_pad_numbers_are_jumpers no)
		(fp_line
			(start -0.7874 -0.4064)
			(end 0.7874 -0.4064)
			(stroke
				(width 0.1524)
				(type default)
			)
			(layer "F.SilkS")
		)
		(fp_line
			(start -0.7874 0.4064)
			(end -0.7874 -0.4064)
			(stroke
				(width 0.1524)
				(type default)
			)
			(layer "F.SilkS")
		)
		(fp_line
			(start 0.7874 -0.4064)
			(end 0.7874 0.4064)
			(stroke
				(width 0.1524)
				(type default)
			)
			(layer "F.SilkS")
		)
		(fp_line
			(start 0.7874 0.4064)
			(end -0.7874 0.4064)
			(stroke
				(width 0.1524)
				(type default)
			)
			(layer "F.SilkS")
		)
		(fp_line
			(start -0.67945 -0.305054)
			(end -0.12065 -0.305054)
			(stroke
				(width 0.1)
				(type default)
			)
			(layer "F.Fab")
		)
		(fp_line
			(start -0.67945 0.3048)
			(end -0.67945 -0.305054)
			(stroke
				(width 0.1)
				(type default)
			)
			(layer "F.Fab")
		)
		(fp_line
			(start -0.12065 -0.305054)
			(end -0.12065 -0.2794)
			(stroke
				(width 0.1)
				(type default)
			)
			(layer "F.Fab")
		)
		(fp_line
			(start -0.12065 -0.2794)
			(end 0.12065 -0.2794)
			(stroke
				(width 0.1)
				(type default)
			)
			(layer "F.Fab")
		)
		(fp_line
			(start -0.12065 0.2794)
			(end -0.12065 0.3048)
			(stroke
				(width 0.1)
				(type default)
			)
			(layer "F.Fab")
		)
		(fp_line
			(start -0.12065 0.3048)
			(end -0.67945 0.3048)
			(stroke
				(width 0.1)
				(type default)
			)
			(layer "F.Fab")
		)
		(fp_line
			(start 0.120396 0.2794)
			(end -0.12065 0.2794)
			(stroke
				(width 0.1)
				(type default)
			)
			(layer "F.Fab")
		)
		(fp_line
			(start 0.120396 0.3048)
			(end 0.120396 0.2794)
			(stroke
				(width 0.1)
				(type default)
			)
			(layer "F.Fab")
		)
		(fp_line
			(start 0.12065 -0.3048)
			(end 0.67945 -0.3048)
			(stroke
				(width 0.1)
				(type default)
			)
			(layer "F.Fab")
		)
		(fp_line
			(start 0.12065 -0.2794)
			(end 0.12065 -0.3048)
			(stroke
				(width 0.1)
				(type default)
			)
			(layer "F.Fab")
		)
		(fp_line
			(start 0.67945 -0.3048)
			(end 0.67945 0.3048)
			(stroke
				(width 0.1)
				(type default)
			)
			(layer "F.Fab")
		)
		(fp_line
			(start 0.67945 0.3048)
			(end 0.120396 0.3048)
			(stroke
				(width 0.1)
				(type default)
			)
			(layer "F.Fab")
		)
		(pad "1" smd circle
			(at -0.40005 0)
			(size 0 0)
			(layers "F.Cu" "F.Mask" "F.Paste")
			(net "CLK_GEN_CK440_PEX_OE6_N")
		)
		(pad "2" smd circle
			(at 0.40005 0)
			(size 0 0)
			(layers "F.Cu" "F.Mask" "F.Paste")
			(net "P3V3")
		)
	)
	(footprint ""
		(layer "F.Cu")
		(at 478.23247 -528.059142 180)
		(property "Reference" "SCREW_SSD2_1"
			(at -5.207 -1.402334 0)
			(unlocked yes)
			(layer "B.SilkS")
			(effects
				(font
					(size 0.7874 0.5842)
					(thickness 0.1524)
				)
				(justify mirror)
			)
		)
		(property "Value" ""
			(at 0 0 180)
			(layer "F.Fab")
			(effects
				(font
					(size 1.27 1.27)
				)
			)
		)
		(duplicate_pad_numbers_are_jumpers no)
		(pad "1" thru_hole circle
			(at 0 0 180)
			(size 0.4572 0.4572)
			(drill 0.2032)
			(layers "*.Cu" "*.Mask")
			(remove_unused_layers no)
			(net "Net_9140")
			(clearance 0.127)
			(thermal_gap 0.127)
			(padstack
				(mode front_inner_back)
				(layer "Inner"
					(shape circle)
					(size 0.4572 0.4572)
					(clearance 0.127)
				)
				(layer "B.Cu"
					(shape circle)
					(size 0.508 0.508)
					(clearance 0.1016)
				)
			)
		)
	)
	(footprint ""
		(layer "F.Cu")
		(at 252.488954 -207.097122 -90)
		(property "Reference" "R5642"
			(at 0 0 270)
			(layer "F.SilkS")
			(hide yes)
			(effects
				(font
					(size 1.27 1.27)
				)
			)
		)
		(property "Value" ""
			(at 0 0 270)
			(layer "F.Fab")
			(effects
				(font
					(size 1.27 1.27)
				)
			)
		)
		(duplicate_pad_numbers_are_jumpers no)
		(fp_line
			(start -0.7874 0.4064)
			(end -0.7874 -0.4064)
			(stroke
				(width 0.1524)
				(type default)
			)
			(layer "F.SilkS")
		)
		(fp_line
			(start 0.7874 0.4064)
			(end -0.7874 0.4064)
			(stroke
				(width 0.1524)
				(type default)
			)
			(layer "F.SilkS")
		)
		(fp_line
			(start -0.7874 -0.4064)
			(end 0.7874 -0.4064)
			(stroke
				(width 0.1524)
				(type default)
			)
			(layer "F.SilkS")
		)
		(fp_line
			(start 0.7874 -0.4064)
			(end 0.7874 0.4064)
			(stroke
				(width 0.1524)
				(type default)
			)
			(layer "F.SilkS")
		)
		(fp_line
			(start -0.67945 0.3048)
			(end -0.67945 -0.305054)
			(stroke
				(width 0.1)
				(type default)
			)
			(layer "F.Fab")
		)
		(fp_line
			(start -0.12065 0.3048)
			(end -0.67945 0.3048)
			(stroke
				(width 0.1)
				(type default)
			)
			(layer "F.Fab")
		)
		(fp_line
			(start 0.120396 0.3048)
			(end 0.120396 0.2794)
			(stroke
				(width 0.1)
				(type default)
			)
			(layer "F.Fab")
		)
		(fp_line
			(start 0.67945 0.3048)
			(end 0.120396 0.3048)
			(stroke
				(width 0.1)
				(type default)
			)
			(layer "F.Fab")
		)
		(fp_line
			(start -0.12065 0.2794)
			(end -0.12065 0.3048)
			(stroke
				(width 0.1)
				(type default)
			)
			(layer "F.Fab")
		)
		(fp_line
			(start 0.120396 0.2794)
			(end -0.12065 0.2794)
			(stroke
				(width 0.1)
				(type default)
			)
			(layer "F.Fab")
		)
		(fp_line
			(start -0.12065 -0.2794)
			(end 0.12065 -0.2794)
			(stroke
				(width 0.1)
				(type default)
			)
			(layer "F.Fab")
		)
		(fp_line
			(start 0.12065 -0.2794)
			(end 0.12065 -0.3048)
			(stroke
				(width 0.1)
				(type default)
			)
			(layer "F.Fab")
		)
		(fp_line
			(start 0.12065 -0.3048)
			(end 0.67945 -0.3048)
			(stroke
				(width 0.1)
				(type default)
			)
			(layer "F.Fab")
		)
		(fp_line
			(start 0.67945 -0.3048)
			(end 0.67945 0.3048)
			(stroke
				(width 0.1)
				(type default)
			)
			(layer "F.Fab")
		)
		(fp_line
			(start -0.67945 -0.305054)
			(end -0.12065 -0.305054)
			(stroke
				(width 0.1)
				(type default)
			)
			(layer "F.Fab")
		)
		(fp_line
			(start -0.12065 -0.305054)
			(end -0.12065 -0.2794)
			(stroke
				(width 0.1)
				(type default)
			)
			(layer "F.Fab")
		)
		(pad "1" smd circle
			(at -0.40005 0 270)
			(size 0 0)
			(layers "F.Cu" "F.Mask" "F.Paste")
			(net "JTAG_BIC_TDO_R")
		)
		(pad "2" smd circle
			(at 0.40005 0 270)
			(size 0 0)
			(layers "F.Cu" "F.Mask" "F.Paste")
			(net "JTAG_BIC_TDO")
		)
	)
)
